(kicad_pcb
	(version 20260206)
	(generator "pcbnew")
	(generator_version "10.0")
	(general
		(thickness 1.6)
		(legacy_teardrops no)
	)
	(paper "A4")
	(title_block
		(title "12092022_DA0F0TMDCD0_F0T_Management_Board_D_brd_V3_OCP.brd")
		(comment 1 "Grand Teton / footprints 655-659 of 1440")
	)
	(layers
		(0 "F.Cu" signal "TOP")
		(4 "In1.Cu" signal "GND")
		(6 "In2.Cu" signal "IN1")
		(8 "In3.Cu" signal "GND1")
		(10 "In4.Cu" signal "IN2")
		(12 "In5.Cu" signal "VCC")
		(14 "In6.Cu" signal "VCC1")
		(16 "In7.Cu" signal "IN3")
		(18 "In8.Cu" signal "GND2")
		(20 "In9.Cu" signal "IN4")
		(22 "In10.Cu" signal "GND3")
		(2 "B.Cu" signal "BOTTOM")
		(9 "F.Adhes" user "F.Adhesive")
		(11 "B.Adhes" user "B.Adhesive")
		(13 "F.Paste" user "Package Geometry/Pastemask Top")
		(15 "B.Paste" user "Package Geometry/Pastemask Bottom")
		(5 "F.SilkS" user "Ref Des/Silkscreen Top")
		(7 "B.SilkS" user "Ref Des/Silkscreen Bottom")
		(1 "F.Mask" user "Board Geometry/Soldermask Top")
		(3 "B.Mask" user "Board Geometry/Soldermask Bottom")
		(17 "Dwgs.User" user "User.Drawings")
		(19 "Cmts.User" user "User.Comments")
		(21 "Eco1.User" user "User.Eco1")
		(23 "Eco2.User" user "User.Eco2")
		(25 "Edge.Cuts" user "Board Geometry/Outline")
		(27 "Margin" user)
		(31 "F.CrtYd" user "Package Geometry/Place Bound Top")
		(29 "B.CrtYd" user "Package Geometry/Place Bound Bottom")
		(35 "F.Fab" user "Ref Des/Assembly Top")
		(33 "B.Fab" user "Ref Des/Assembly Bottom")
	)
	(footprint ""
		(layer "F.Cu")
		(at 6.7818 -80.4926 180)
		(property "Reference" "C34"
			(at 0 0 180)
			(layer "F.SilkS")
			(hide yes)
			(effects
				(font
					(size 1.27 1.27)
				)
			)
		)
		(property "Value" ""
			(at 0 0 180)
			(layer "F.Fab")
			(effects
				(font
					(size 1.27 1.27)
				)
			)
		)
		(duplicate_pad_numbers_are_jumpers no)
		(fp_line
			(start 0.7874 0.4064)
			(end -0.7874 0.4064)
			(stroke
				(width 0.1524)
				(type default)
			)
			(layer "F.SilkS")
		)
		(fp_line
			(start 0.7874 -0.4064)
			(end 0.7874 0.4064)
			(stroke
				(width 0.1524)
				(type default)
			)
			(layer "F.SilkS")
		)
		(fp_line
			(start -0.7874 0.4064)
			(end -0.7874 -0.4064)
			(stroke
				(width 0.1524)
				(type default)
			)
			(layer "F.SilkS")
		)
		(fp_line
			(start -0.7874 -0.4064)
			(end 0.7874 -0.4064)
			(stroke
				(width 0.1524)
				(type default)
			)
			(layer "F.SilkS")
		)
		(fp_line
			(start 0.67945 0.3048)
			(end 0.120396 0.3048)
			(stroke
				(width 0.1)
				(type default)
			)
			(layer "F.Fab")
		)
		(fp_line
			(start 0.67945 -0.3048)
			(end 0.67945 0.3048)
			(stroke
				(width 0.1)
				(type default)
			)
			(layer "F.Fab")
		)
		(fp_line
			(start 0.12065 -0.2794)
			(end 0.12065 -0.3048)
			(stroke
				(width 0.1)
				(type default)
			)
			(layer "F.Fab")
		)
		(fp_line
			(start 0.12065 -0.3048)
			(end 0.67945 -0.3048)
			(stroke
				(width 0.1)
				(type default)
			)
			(layer "F.Fab")
		)
		(fp_line
			(start 0.120396 0.3048)
			(end 0.120396 0.2794)
			(stroke
				(width 0.1)
				(type default)
			)
			(layer "F.Fab")
		)
		(fp_line
			(start 0.120396 0.2794)
			(end -0.12065 0.2794)
			(stroke
				(width 0.1)
				(type default)
			)
			(layer "F.Fab")
		)
		(fp_line
			(start -0.12065 0.3048)
			(end -0.67945 0.3048)
			(stroke
				(width 0.1)
				(type default)
			)
			(layer "F.Fab")
		)
		(fp_line
			(start -0.12065 0.2794)
			(end -0.12065 0.3048)
			(stroke
				(width 0.1)
				(type default)
			)
			(layer "F.Fab")
		)
		(fp_line
			(start -0.12065 -0.2794)
			(end 0.12065 -0.2794)
			(stroke
				(width 0.1)
				(type default)
			)
			(layer "F.Fab")
		)
		(fp_line
			(start -0.12065 -0.305054)
			(end -0.12065 -0.2794)
			(stroke
				(width 0.1)
				(type default)
			)
			(layer "F.Fab")
		)
		(fp_line
			(start -0.67945 0.3048)
			(end -0.67945 -0.305054)
			(stroke
				(width 0.1)
				(type default)
			)
			(layer "F.Fab")
		)
		(fp_line
			(start -0.67945 -0.305054)
			(end -0.12065 -0.305054)
			(stroke
				(width 0.1)
				(type default)
			)
			(layer "F.Fab")
		)
		(pad "1" smd circle
			(at -0.40005 0 180)
			(size 0 0)
			(layers "F.Cu" "F.Mask" "F.Paste")
			(net "P3V3_AUX")
		)
		(pad "2" smd circle
			(at 0.40005 0 180)
			(size 0 0)
			(layers "F.Cu" "F.Mask" "F.Paste")
			(net "GND")
		)
	)
	(footprint ""
		(layer "F.Cu")
		(at 28.27401 -16.50365 90)
		(property "Reference" "L23"
			(at 0 0 90)
			(layer "F.SilkS")
			(hide yes)
			(effects
				(font
					(size 1.27 1.27)
				)
			)
		)
		(property "Value" ""
			(at 0 0 90)
			(layer "F.Fab")
			(effects
				(font
					(size 1.27 1.27)
				)
			)
		)
		(duplicate_pad_numbers_are_jumpers no)
		(fp_line
			(start 0.8636 -1.524)
			(end 0.8636 1.524)
			(stroke
				(width 0.1524)
				(type default)
			)
			(layer "F.SilkS")
		)
		(fp_line
			(start 0.38481 -1.524)
			(end 0.8636 -1.524)
			(stroke
				(width 0.1524)
				(type default)
			)
			(layer "F.SilkS")
		)
		(fp_line
			(start -0.8636 -1.524)
			(end -0.40767 -1.524)
			(stroke
				(width 0.1524)
				(type default)
			)
			(layer "F.SilkS")
		)
		(fp_line
			(start 0.8636 1.524)
			(end 0.49403 1.524)
			(stroke
				(width 0.1524)
				(type default)
			)
			(layer "F.SilkS")
		)
		(fp_line
			(start -0.45593 1.524)
			(end -0.8636 1.524)
			(stroke
				(width 0.1524)
				(type default)
			)
			(layer "F.SilkS")
		)
		(fp_line
			(start -0.8636 1.524)
			(end -0.8636 -1.524)
			(stroke
				(width 0.1524)
				(type default)
			)
			(layer "F.SilkS")
		)
		(fp_poly
			(pts
				(xy -1.1049 -1.06426) (xy -1.6129 -0.810514) (xy -1.6129 -1.31826)
			)
			(stroke
				(width 0)
				(type default)
			)
			(fill yes)
			(layer "F.SilkS")
		)
		(fp_line
			(start 0.700024 -1.100074)
			(end 0.700024 1.100074)
			(stroke
				(width 0.1)
				(type default)
			)
			(layer "F.Fab")
		)
		(fp_line
			(start -0.700024 -1.100074)
			(end 0.700024 -1.100074)
			(stroke
				(width 0.1)
				(type default)
			)
			(layer "F.Fab")
		)
		(fp_line
			(start 0.700024 1.100074)
			(end -0.700024 1.100074)
			(stroke
				(width 0.1)
				(type default)
			)
			(layer "F.Fab")
		)
		(fp_line
			(start -0.700024 1.100074)
			(end -0.700024 -1.100074)
			(stroke
				(width 0.1)
				(type default)
			)
			(layer "F.Fab")
		)
		(fp_poly
			(pts
				(xy -0.4572 -1.6256) (xy -0.7112 -2.1336) (xy -0.2032 -2.1336)
			)
			(stroke
				(width 0)
				(type default)
			)
			(fill yes)
			(layer "F.Fab")
		)
		(pad "1" smd rect
			(at -0.424942 -0.849884 90)
			(size 0.3556 0.9144)
			(layers "F.Cu" "F.Mask" "F.Paste")
			(net "USB_FPNL_DP")
		)
		(pad "2" smd rect
			(at -0.424942 0.849884 90)
			(size 0.3556 0.9144)
			(layers "F.Cu" "F.Mask" "F.Paste")
			(net "USB2_01_F_DP")
		)
		(pad "3" smd rect
			(at 0.424942 0.849884 90)
			(size 0.3556 0.9144)
			(layers "F.Cu" "F.Mask" "F.Paste")
			(net "USB2_01_F_DN")
		)
		(pad "4" smd rect
			(at 0.424942 -0.849884 90)
			(size 0.3556 0.9144)
			(layers "F.Cu" "F.Mask" "F.Paste")
			(net "USB_FPNL_DN")
		)
	)
	(footprint ""
		(layer "F.Cu")
		(at 44.704 -109.8804)
		(property "Reference" "R82"
			(at 0 0 0)
			(layer "F.SilkS")
			(hide yes)
			(effects
				(font
					(size 1.27 1.27)
				)
			)
		)
		(property "Value" ""
			(at 0 0 0)
			(layer "F.Fab")
			(effects
				(font
					(size 1.27 1.27)
				)
			)
		)
		(duplicate_pad_numbers_are_jumpers no)
		(fp_line
			(start -0.7874 -0.4064)
			(end 0.7874 -0.4064)
			(stroke
				(width 0.1524)
				(type default)
			)
			(layer "F.SilkS")
		)
		(fp_line
			(start -0.7874 0.4064)
			(end -0.7874 -0.4064)
			(stroke
				(width 0.1524)
				(type default)
			)
			(layer "F.SilkS")
		)
		(fp_line
			(start 0.7874 -0.4064)
			(end 0.7874 0.4064)
			(stroke
				(width 0.1524)
				(type default)
			)
			(layer "F.SilkS")
		)
		(fp_line
			(start 0.7874 0.4064)
			(end -0.7874 0.4064)
			(stroke
				(width 0.1524)
				(type default)
			)
			(layer "F.SilkS")
		)
		(fp_line
			(start -0.67945 -0.305054)
			(end -0.12065 -0.305054)
			(stroke
				(width 0.1)
				(type default)
			)
			(layer "F.Fab")
		)
		(fp_line
			(start -0.67945 0.3048)
			(end -0.67945 -0.305054)
			(stroke
				(width 0.1)
				(type default)
			)
			(layer "F.Fab")
		)
		(fp_line
			(start -0.12065 -0.305054)
			(end -0.12065 -0.2794)
			(stroke
				(width 0.1)
				(type default)
			)
			(layer "F.Fab")
		)
		(fp_line
			(start -0.12065 -0.2794)
			(end 0.12065 -0.2794)
			(stroke
				(width 0.1)
				(type default)
			)
			(layer "F.Fab")
		)
		(fp_line
			(start -0.12065 0.2794)
			(end -0.12065 0.3048)
			(stroke
				(width 0.1)
				(type default)
			)
			(layer "F.Fab")
		)
		(fp_line
			(start -0.12065 0.3048)
			(end -0.67945 0.3048)
			(stroke
				(width 0.1)
				(type default)
			)
			(layer "F.Fab")
		)
		(fp_line
			(start 0.120396 0.2794)
			(end -0.12065 0.2794)
			(stroke
				(width 0.1)
				(type default)
			)
			(layer "F.Fab")
		)
		(fp_line
			(start 0.120396 0.3048)
			(end 0.120396 0.2794)
			(stroke
				(width 0.1)
				(type default)
			)
			(layer "F.Fab")
		)
		(fp_line
			(start 0.12065 -0.3048)
			(end 0.67945 -0.3048)
			(stroke
				(width 0.1)
				(type default)
			)
			(layer "F.Fab")
		)
		(fp_line
			(start 0.12065 -0.2794)
			(end 0.12065 -0.3048)
			(stroke
				(width 0.1)
				(type default)
			)
			(layer "F.Fab")
		)
		(fp_line
			(start 0.67945 -0.3048)
			(end 0.67945 0.3048)
			(stroke
				(width 0.1)
				(type default)
			)
			(layer "F.Fab")
		)
		(fp_line
			(start 0.67945 0.3048)
			(end 0.120396 0.3048)
			(stroke
				(width 0.1)
				(type default)
			)
			(layer "F.Fab")
		)
		(pad "1" smd circle
			(at -0.40005 0)
			(size 0 0)
			(layers "F.Cu" "F.Mask" "F.Paste")
			(net "P3V3_AUX")
		)
		(pad "2" smd circle
			(at 0.40005 0)
			(size 0 0)
			(layers "F.Cu" "F.Mask" "F.Paste")
			(net "SGPIO_CLK_0")
		)
	)
	(footprint ""
		(layer "F.Cu")
		(at 101.2825 -65.6336 90)
		(property "Reference" "J9"
			(at -5.1816 -1.56083 90)
			(unlocked yes)
			(layer "F.SilkS")
			(effects
				(font
					(size 0.7874 0.5842)
					(thickness 0.1524)
				)
				(justify left)
			)
		)
		(property "Value" ""
			(at 0 0 90)
			(layer "F.Fab")
			(effects
				(font
					(size 1.27 1.27)
				)
			)
		)
		(duplicate_pad_numbers_are_jumpers no)
		(fp_line
			(start 1.2192 -2.1082)
			(end 1.2192 -0.462026)
			(stroke
				(width 0.1524)
				(type default)
			)
			(layer "F.SilkS")
		)
		(fp_line
			(start -1.2192 -2.1082)
			(end 1.2192 -2.1082)
			(stroke
				(width 0.1524)
				(type default)
			)
			(layer "F.SilkS")
		)
		(fp_line
			(start 1.2192 0.454406)
			(end 1.2192 2.1082)
			(stroke
				(width 0.1524)
				(type default)
			)
			(layer "F.SilkS")
		)
		(fp_line
			(start 1.2192 2.1082)
			(end -1.2192 2.1082)
			(stroke
				(width 0.1524)
				(type default)
			)
			(layer "F.SilkS")
		)
		(fp_line
			(start -1.2192 2.1082)
			(end -1.2192 -2.1082)
			(stroke
				(width 0.1524)
				(type default)
			)
			(layer "F.SilkS")
		)
		(pad "" np_thru_hole circle
			(at -2.8829 -1.27)
			(size 1.0414 1.0414)
			(drill 1.0414)
			(layers "*.Cu" "*.Mask")
			(clearance 0.381)
			(thermal_gap 0.381)
		)
		(pad "" np_thru_hole circle
			(at -2.8829 1.27)
			(size 1.0414 1.0414)
			(drill 1.0414)
			(layers "*.Cu" "*.Mask")
			(clearance 0.381)
			(thermal_gap 0.381)
		)
		(pad "" np_thru_hole circle
			(at 3.4671 -1.27)
			(size 1.0414 1.0414)
			(drill 1.0414)
			(layers "*.Cu" "*.Mask")
			(clearance 0.381)
			(thermal_gap 0.381)
		)
		(pad "" np_thru_hole circle
			(at 3.4671 1.27)
			(size 1.0414 1.0414)
			(drill 1.0414)
			(layers "*.Cu" "*.Mask")
			(clearance 0.381)
			(thermal_gap 0.381)
		)
		(pad "1" smd rect
			(at 0.8255 -0.249936)
			(size 0.3048 0.508)
			(layers "F.Cu" "F.Mask" "F.Paste")
			(net "85_5INCH_TOP_DN")
		)
		(pad "2" smd rect
			(at 0.8255 0.249936)
			(size 0.3048 0.508)
			(layers "F.Cu" "F.Mask" "F.Paste")
			(net "85_5INCH_TOP_DP")
		)
		(pad "3" smd circle
			(at 0 0 90)
			(size 0 0)
			(layers "F.Cu" "F.Mask" "F.Paste")
			(net "GND_P1")
		)
		(zone
			(layer "F.Cu")
			(hatch none 0.5)
			(connect_pads
				(clearance 0)
			)
			(min_thickness 0.25)
			(keepout
				(tracks not_allowed)
				(vias allowed)
				(pads allowed)
				(copperpour not_allowed)
				(footprints allowed)
			)
			(placement
				(enabled no)
				(sheetname "")
			)
			(fill
				(thermal_gap 0.5)
				(thermal_bridge_width 0.5)
				(island_removal_mode 0)
			)
			(polygon
				(pts
					(xy 100.73386 -66.7512) (xy 100.829364 -66.7512) (xy 100.829364 -66.1543) (xy 101.235764 -66.1543)
					(xy 101.235764 -66.7512) (xy 101.329236 -66.7512) (xy 101.329236 -66.1543) (xy 101.735636 -66.1543)
					(xy 101.735636 -66.7512) (xy 101.83114 -66.7512) (xy 101.83114 -66.0527) (xy 100.73386 -66.0527)
				)
			)
		)
		(zone
			(layers "F.Cu" "B.Cu" "In1.Cu" "In2.Cu" "In3.Cu" "In4.Cu" "In5.Cu" "In6.Cu"
				"In7.Cu" "In8.Cu" "In9.Cu" "In10.Cu"
			)
			(hatch none 0.5)
			(connect_pads
				(clearance 0)
			)
			(min_thickness 0.25)
			(keepout
				(tracks not_allowed)
				(vias allowed)
				(pads allowed)
				(copperpour not_allowed)
				(footprints allowed)
			)
			(placement
				(enabled no)
				(sheetname "")
			)
			(fill
				(thermal_gap 0.5)
				(thermal_bridge_width 0.5)
				(island_removal_mode 0)
			)
			(polygon
				(pts
					(arc
						(start 100.9396 -69.1007)
						(mid 99.0854 -69.1007)
						(end 100.9396 -69.1007)
					)
				)
			)
		)
		(zone
			(layers "F.Cu" "B.Cu" "In1.Cu" "In2.Cu" "In3.Cu" "In4.Cu" "In5.Cu" "In6.Cu"
				"In7.Cu" "In8.Cu" "In9.Cu" "In10.Cu"
			)
			(hatch none 0.5)
			(connect_pads
				(clearance 0)
			)
			(min_thickness 0.25)
			(keepout
				(tracks not_allowed)
				(vias allowed)
				(pads allowed)
				(copperpour not_allowed)
				(footprints allowed)
			)
			(placement
				(enabled no)
				(sheetname "")
			)
			(fill
				(thermal_gap 0.5)
				(thermal_bridge_width 0.5)
				(island_removal_mode 0)
			)
			(polygon
				(pts
					(arc
						(start 100.9396 -62.7507)
						(mid 99.0854 -62.7507)
						(end 100.9396 -62.7507)
					)
				)
			)
		)
		(zone
			(layers "F.Cu" "B.Cu" "In1.Cu" "In2.Cu" "In3.Cu" "In4.Cu" "In5.Cu" "In6.Cu"
				"In7.Cu" "In8.Cu" "In9.Cu" "In10.Cu"
			)
			(hatch none 0.5)
			(connect_pads
				(clearance 0)
			)
			(min_thickness 0.25)
			(keepout
				(tracks not_allowed)
				(vias allowed)
				(pads allowed)
				(copperpour not_allowed)
				(footprints allowed)
			)
			(placement
				(enabled no)
				(sheetname "")
			)
			(fill
				(thermal_gap 0.5)
				(thermal_bridge_width 0.5)
				(island_removal_mode 0)
			)
			(polygon
				(pts
					(arc
						(start 103.4796 -69.1007)
						(mid 101.6254 -69.1007)
						(end 103.4796 -69.1007)
					)
				)
			)
		)
		(zone
			(layers "F.Cu" "B.Cu" "In1.Cu" "In2.Cu" "In3.Cu" "In4.Cu" "In5.Cu" "In6.Cu"
				"In7.Cu" "In8.Cu" "In9.Cu" "In10.Cu"
			)
			(hatch none 0.5)
			(connect_pads
				(clearance 0)
			)
			(min_thickness 0.25)
			(keepout
				(tracks not_allowed)
				(vias allowed)
				(pads allowed)
				(copperpour not_allowed)
				(footprints allowed)
			)
			(placement
				(enabled no)
				(sheetname "")
			)
			(fill
				(thermal_gap 0.5)
				(thermal_bridge_width 0.5)
				(island_removal_mode 0)
			)
			(polygon
				(pts
					(arc
						(start 103.4796 -62.7507)
						(mid 101.6254 -62.7507)
						(end 103.4796 -62.7507)
					)
				)
			)
		)
	)
	(footprint ""
		(layer "F.Cu")
		(at 77.851 -79.121)
		(property "Reference" "C227"
			(at 0 0 0)
			(layer "F.SilkS")
			(hide yes)
			(effects
				(font
					(size 1.27 1.27)
				)
			)
		)
		(property "Value" ""
			(at 0 0 0)
			(layer "F.Fab")
			(effects
				(font
					(size 1.27 1.27)
				)
			)
		)
		(duplicate_pad_numbers_are_jumpers no)
		(fp_line
			(start -0.7874 -0.4064)
			(end 0.7874 -0.4064)
			(stroke
				(width 0.1524)
				(type default)
			)
			(layer "F.SilkS")
		)
		(fp_line
			(start -0.7874 0.4064)
			(end -0.7874 -0.4064)
			(stroke
				(width 0.1524)
				(type default)
			)
			(layer "F.SilkS")
		)
		(fp_line
			(start 0.7874 -0.4064)
			(end 0.7874 0.4064)
			(stroke
				(width 0.1524)
				(type default)
			)
			(layer "F.SilkS")
		)
		(fp_line
			(start 0.7874 0.4064)
			(end -0.7874 0.4064)
			(stroke
				(width 0.1524)
				(type default)
			)
			(layer "F.SilkS")
		)
		(fp_line
			(start -0.67945 -0.305054)
			(end -0.12065 -0.305054)
			(stroke
				(width 0.1)
				(type default)
			)
			(layer "F.Fab")
		)
		(fp_line
			(start -0.67945 0.3048)
			(end -0.67945 -0.305054)
			(stroke
				(width 0.1)
				(type default)
			)
			(layer "F.Fab")
		)
		(fp_line
			(start -0.12065 -0.305054)
			(end -0.12065 -0.2794)
			(stroke
				(width 0.1)
				(type default)
			)
			(layer "F.Fab")
		)
		(fp_line
			(start -0.12065 -0.2794)
			(end 0.12065 -0.2794)
			(stroke
				(width 0.1)
				(type default)
			)
			(layer "F.Fab")
		)
		(fp_line
			(start -0.12065 0.2794)
			(end -0.12065 0.3048)
			(stroke
				(width 0.1)
				(type default)
			)
			(layer "F.Fab")
		)
		(fp_line
			(start -0.12065 0.3048)
			(end -0.67945 0.3048)
			(stroke
				(width 0.1)
				(type default)
			)
			(layer "F.Fab")
		)
		(fp_line
			(start 0.120396 0.2794)
			(end -0.12065 0.2794)
			(stroke
				(width 0.1)
				(type default)
			)
			(layer "F.Fab")
		)
		(fp_line
			(start 0.120396 0.3048)
			(end 0.120396 0.2794)
			(stroke
				(width 0.1)
				(type default)
			)
			(layer "F.Fab")
		)
		(fp_line
			(start 0.12065 -0.3048)
			(end 0.67945 -0.3048)
			(stroke
				(width 0.1)
				(type default)
			)
			(layer "F.Fab")
		)
		(fp_line
			(start 0.12065 -0.2794)
			(end 0.12065 -0.3048)
			(stroke
				(width 0.1)
				(type default)
			)
			(layer "F.Fab")
		)
		(fp_line
			(start 0.67945 -0.3048)
			(end 0.67945 0.3048)
			(stroke
				(width 0.1)
				(type default)
			)
			(layer "F.Fab")
		)
		(fp_line
			(start 0.67945 0.3048)
			(end 0.120396 0.3048)
			(stroke
				(width 0.1)
				(type default)
			)
			(layer "F.Fab")
		)
		(pad "1" smd circle
			(at -0.40005 0)
			(size 0 0)
			(layers "F.Cu" "F.Mask" "F.Paste")
			(net "P3V3_LDO")
		)
		(pad "2" smd circle
			(at 0.40005 0)
			(size 0 0)
			(layers "F.Cu" "F.Mask" "F.Paste")
			(net "GND")
		)
	)
)
